(kicad_pcb
	(version 20240108)
	(generator "pcbnew")
	(generator_version "8.0")
	(general
		(thickness 1.62)
		(legacy_teardrops no)
	)
	(paper "A4")
	(title_block
		(title "Jetson Orin Baseboard")
		(date "2025-03-12")
		(rev "1.3.4")
		(company "Antmicro Ltd")
		(comment 1 "www.antmicro.com")
		(comment 9 "footprints 19-22 of 677")
	)
	(layers
		(0 "F.Cu" signal)
		(1 "In1.Cu" signal)
		(2 "In2.Cu" signal)
		(3 "In3.Cu" signal)
		(4 "In4.Cu" jumper)
		(5 "In5.Cu" signal)
		(6 "In6.Cu" signal)
		(31 "B.Cu" signal)
		(32 "B.Adhes" user "B.Adhesive")
		(33 "F.Adhes" user "F.Adhesive")
		(34 "B.Paste" user)
		(35 "F.Paste" user)
		(36 "B.SilkS" user "B.Silkscreen")
		(37 "F.SilkS" user "F.Silkscreen")
		(38 "B.Mask" user)
		(39 "F.Mask" user)
		(40 "Dwgs.User" user "User.Drawings")
		(41 "Cmts.User" user "User.Comments")
		(42 "Eco1.User" user "User.Eco1")
		(43 "Eco2.User" user "User.Eco2")
		(44 "Edge.Cuts" user)
		(45 "Margin" user)
		(46 "B.CrtYd" user "B.Courtyard")
		(47 "F.CrtYd" user "F.Courtyard")
		(48 "B.Fab" user)
		(49 "F.Fab" user)
	)
	(footprint "antmicro-footprints:C_0402_1005Metric"
		(layer "F.Cu")
		(at 79.9 106.25)
		(descr "Capacitor SMD 0402")
		(tags "capacitor SMD 0402")
		(property "Reference" "C36"
			(at -1.15 -0.45 0)
			(layer "F.SilkS")
			(effects
				(font
					(size 0.7 0.7)
					(thickness 0.15)
				)
				(justify left bottom)
			)
		)
		(property "Value" "C_100n_0402"
			(at 0 1.4 0)
			(layer "F.Fab")
			(effects
				(font
					(size 0.7 0.7)
					(thickness 0.15)
				)
				(justify left bottom)
			)
		)
		(property "Footprint" "antmicro-footprints:C_0402_1005Metric"
			(at 0 0 0)
			(layer "F.Fab")
			(hide yes)
			(effects
				(font
					(size 1.27 1.27)
					(thickness 0.15)
				)
			)
		)
		(property "Datasheet" "https://www.murata.com/products/productdetail?partno=GRM155R61H104KE14%23"
			(at 0 0 0)
			(layer "F.Fab")
			(hide yes)
			(effects
				(font
					(size 1.27 1.27)
					(thickness 0.15)
				)
			)
		)
		(property "Author" "Antmicro"
			(at 0 0 0)
			(layer "F.Fab")
			(hide yes)
			(effects
				(font
					(size 1 1)
					(thickness 0.15)
				)
			)
		)
		(property "Dielectric" "X5R"
			(at 0 0 0)
			(layer "F.Fab")
			(hide yes)
			(effects
				(font
					(size 1 1)
					(thickness 0.15)
				)
			)
		)
		(property "License" "Apache-2.0"
			(at 0 0 0)
			(layer "F.Fab")
			(hide yes)
			(effects
				(font
					(size 1 1)
					(thickness 0.15)
				)
			)
		)
		(property "MPN" "GRM155R61H104KE14D"
			(at 0 0 0)
			(layer "F.Fab")
			(hide yes)
			(effects
				(font
					(size 1 1)
					(thickness 0.15)
				)
			)
		)
		(property "Manufacturer" "Murata"
			(at 0 0 0)
			(layer "F.Fab")
			(hide yes)
			(effects
				(font
					(size 1 1)
					(thickness 0.15)
				)
			)
		)
		(property "Val" "100n"
			(at 0 0 0)
			(layer "F.Fab")
			(hide yes)
			(effects
				(font
					(size 1 1)
					(thickness 0.15)
				)
			)
		)
		(property "Voltage" "50V"
			(at 0 0 0)
			(layer "F.Fab")
			(hide yes)
			(effects
				(font
					(size 1 1)
					(thickness 0.15)
				)
			)
		)
		(sheetname "USB Debug, DP")
		(sheetfile "usb.kicad_sch")
		(attr smd)
		(fp_rect
			(start -0.925 -0.47)
			(end 0.925 0.47)
			(stroke
				(width 0.05)
				(type default)
			)
			(fill none)
			(layer "F.CrtYd")
		)
		(fp_line
			(start -0.494 -0.25)
			(end 0.504 -0.25)
			(stroke
				(width 0.15)
				(type solid)
			)
			(layer "F.Fab")
		)
		(fp_line
			(start -0.494 0.248)
			(end -0.494 -0.25)
			(stroke
				(width 0.15)
				(type solid)
			)
			(layer "F.Fab")
		)
		(fp_line
			(start 0.504 -0.25)
			(end 0.504 0.248)
			(stroke
				(width 0.15)
				(type solid)
			)
			(layer "F.Fab")
		)
		(fp_line
			(start 0.504 0.248)
			(end -0.494 0.248)
			(stroke
				(width 0.15)
				(type solid)
			)
			(layer "F.Fab")
		)
		(fp_text user "License: Apache-2.0"
			(at -0.932 5.17 0)
			(layer "F.Fab")
			(hide yes)
			(effects
				(font
					(size 0.7 0.7)
					(thickness 0.15)
				)
				(justify left bottom)
			)
		)
		(fp_text user "${REFERENCE}"
			(at -0.932 3.168 0)
			(layer "F.Fab")
			(hide yes)
			(effects
				(font
					(size 0.7 0.7)
					(thickness 0.15)
				)
				(justify left bottom)
			)
		)
		(fp_text user "Author: Antmicro"
			(at -0.932 4.17 0)
			(layer "F.Fab")
			(hide yes)
			(effects
				(font
					(size 0.7 0.7)
					(thickness 0.15)
				)
				(justify left bottom)
			)
		)
		(pad "1" smd roundrect
			(at -0.48 0)
			(size 0.59 0.64)
			(layers "F.Cu" "F.Paste" "F.Mask")
			(roundrect_rratio 0.25)
			(net 87 "+3V3")
			(pintype "passive")
		)
		(pad "2" smd roundrect
			(at 0.48 0)
			(size 0.59 0.64)
			(layers "F.Cu" "F.Paste" "F.Mask")
			(roundrect_rratio 0.25)
			(net 1 "GND")
			(pintype "passive")
		)
	)
	(footprint "antmicro-footprints:C_0402_1005Metric"
		(layer "F.Cu")
		(at 101.2 122.4 -90)
		(descr "Capacitor SMD 0402")
		(tags "capacitor SMD 0402")
		(property "Reference" "C75"
			(at 0.95 0.35 -90)
			(layer "F.SilkS")
			(effects
				(font
					(size 0.7 0.7)
					(thickness 0.15)
				)
				(justify left bottom)
			)
		)
		(property "Value" "C_100n_0402"
			(at 0 1.4 -90)
			(layer "F.Fab")
			(effects
				(font
					(size 0.7 0.7)
					(thickness 0.15)
				)
				(justify left bottom)
			)
		)
		(property "Footprint" "antmicro-footprints:C_0402_1005Metric"
			(at 0 0 -90)
			(layer "F.Fab")
			(hide yes)
			(effects
				(font
					(size 1.27 1.27)
					(thickness 0.15)
				)
			)
		)
		(property "Datasheet" "https://www.murata.com/products/productdetail?partno=GRM155R61H104KE14%23"
			(at 0 0 -90)
			(layer "F.Fab")
			(hide yes)
			(effects
				(font
					(size 1.27 1.27)
					(thickness 0.15)
				)
			)
		)
		(property "Author" "Antmicro"
			(at -21.2 223.6 0)
			(layer "F.Fab")
			(hide yes)
			(effects
				(font
					(size 1 1)
					(thickness 0.15)
				)
			)
		)
		(property "Dielectric" "X5R"
			(at -21.2 223.6 0)
			(layer "F.Fab")
			(hide yes)
			(effects
				(font
					(size 1 1)
					(thickness 0.15)
				)
			)
		)
		(property "License" "Apache-2.0"
			(at -21.2 223.6 0)
			(layer "F.Fab")
			(hide yes)
			(effects
				(font
					(size 1 1)
					(thickness 0.15)
				)
			)
		)
		(property "MPN" "GRM155R61H104KE14D"
			(at -21.2 223.6 0)
			(layer "F.Fab")
			(hide yes)
			(effects
				(font
					(size 1 1)
					(thickness 0.15)
				)
			)
		)
		(property "Manufacturer" "Murata"
			(at -21.2 223.6 0)
			(layer "F.Fab")
			(hide yes)
			(effects
				(font
					(size 1 1)
					(thickness 0.15)
				)
			)
		)
		(property "Val" "100n"
			(at -21.2 223.6 0)
			(layer "F.Fab")
			(hide yes)
			(effects
				(font
					(size 1 1)
					(thickness 0.15)
				)
			)
		)
		(property "Voltage" "50V"
			(at -21.2 223.6 0)
			(layer "F.Fab")
			(hide yes)
			(effects
				(font
					(size 1 1)
					(thickness 0.15)
				)
			)
		)
		(sheetname "USB3")
		(sheetfile "usb3.kicad_sch")
		(attr smd)
		(fp_rect
			(start -0.925 -0.47)
			(end 0.925 0.47)
			(stroke
				(width 0.05)
				(type default)
			)
			(fill none)
			(layer "F.CrtYd")
		)
		(fp_line
			(start -0.494 0.248)
			(end -0.494 -0.25)
			(stroke
				(width 0.15)
				(type solid)
			)
			(layer "F.Fab")
		)
		(fp_line
			(start 0.504 0.248)
			(end -0.494 0.248)
			(stroke
				(width 0.15)
				(type solid)
			)
			(layer "F.Fab")
		)
		(fp_line
			(start -0.494 -0.25)
			(end 0.504 -0.25)
			(stroke
				(width 0.15)
				(type solid)
			)
			(layer "F.Fab")
		)
		(fp_line
			(start 0.504 -0.25)
			(end 0.504 0.248)
			(stroke
				(width 0.15)
				(type solid)
			)
			(layer "F.Fab")
		)
		(fp_text user "${REFERENCE}"
			(at -0.932 3.168 -90)
			(layer "F.Fab")
			(hide yes)
			(effects
				(font
					(size 0.7 0.7)
					(thickness 0.15)
				)
				(justify left bottom)
			)
		)
		(fp_text user "License: Apache-2.0"
			(at -0.932 5.17 -90)
			(layer "F.Fab")
			(hide yes)
			(effects
				(font
					(size 0.7 0.7)
					(thickness 0.15)
				)
				(justify left bottom)
			)
		)
		(fp_text user "Author: Antmicro"
			(at -0.932 4.17 -90)
			(layer "F.Fab")
			(hide yes)
			(effects
				(font
					(size 0.7 0.7)
					(thickness 0.15)
				)
				(justify left bottom)
			)
		)
		(pad "1" smd roundrect
			(at -0.48 0 270)
			(size 0.59 0.64)
			(layers "F.Cu" "F.Paste" "F.Mask")
			(roundrect_rratio 0.25)
			(net 270 "/USB3/USBC1_VBUS")
			(pintype "passive")
		)
		(pad "2" smd roundrect
			(at 0.48 0 270)
			(size 0.59 0.64)
			(layers "F.Cu" "F.Paste" "F.Mask")
			(roundrect_rratio 0.25)
			(net 1 "GND")
			(pintype "passive")
		)
	)
	(footprint "antmicro-footprints:C_0402_1005Metric"
		(layer "F.Cu")
		(at 101.2 115.8 90)
		(descr "Capacitor SMD 0402")
		(tags "capacitor SMD 0402")
		(property "Reference" "C73"
			(at 1.05 0.45 90)
			(layer "F.SilkS")
			(effects
				(font
					(size 0.7 0.7)
					(thickness 0.15)
				)
				(justify left bottom)
			)
		)
		(property "Value" "C_100n_0402"
			(at 0 1.4 90)
			(layer "F.Fab")
			(effects
				(font
					(size 0.7 0.7)
					(thickness 0.15)
				)
				(justify left bottom)
			)
		)
		(property "Footprint" "antmicro-footprints:C_0402_1005Metric"
			(at 0 0 90)
			(layer "F.Fab")
			(hide yes)
			(effects
				(font
					(size 1.27 1.27)
					(thickness 0.15)
				)
			)
		)
		(property "Datasheet" "https://www.murata.com/products/productdetail?partno=GRM155R61H104KE14%23"
			(at 0 0 90)
			(layer "F.Fab")
			(hide yes)
			(effects
				(font
					(size 1.27 1.27)
					(thickness 0.15)
				)
			)
		)
		(property "Author" "Antmicro"
			(at 217 14.6 0)
			(layer "F.Fab")
			(hide yes)
			(effects
				(font
					(size 1 1)
					(thickness 0.15)
				)
			)
		)
		(property "Dielectric" "X5R"
			(at 217 14.6 0)
			(layer "F.Fab")
			(hide yes)
			(effects
				(font
					(size 1 1)
					(thickness 0.15)
				)
			)
		)
		(property "License" "Apache-2.0"
			(at 217 14.6 0)
			(layer "F.Fab")
			(hide yes)
			(effects
				(font
					(size 1 1)
					(thickness 0.15)
				)
			)
		)
		(property "MPN" "GRM155R61H104KE14D"
			(at 217 14.6 0)
			(layer "F.Fab")
			(hide yes)
			(effects
				(font
					(size 1 1)
					(thickness 0.15)
				)
			)
		)
		(property "Manufacturer" "Murata"
			(at 217 14.6 0)
			(layer "F.Fab")
			(hide yes)
			(effects
				(font
					(size 1 1)
					(thickness 0.15)
				)
			)
		)
		(property "Val" "100n"
			(at 217 14.6 0)
			(layer "F.Fab")
			(hide yes)
			(effects
				(font
					(size 1 1)
					(thickness 0.15)
				)
			)
		)
		(property "Voltage" "50V"
			(at 217 14.6 0)
			(layer "F.Fab")
			(hide yes)
			(effects
				(font
					(size 1 1)
					(thickness 0.15)
				)
			)
		)
		(sheetname "USB3")
		(sheetfile "usb3.kicad_sch")
		(attr smd)
		(fp_rect
			(start -0.925 -0.47)
			(end 0.925 0.47)
			(stroke
				(width 0.05)
				(type default)
			)
			(fill none)
			(layer "F.CrtYd")
		)
		(fp_line
			(start 0.504 -0.25)
			(end 0.504 0.248)
			(stroke
				(width 0.15)
				(type solid)
			)
			(layer "F.Fab")
		)
		(fp_line
			(start -0.494 -0.25)
			(end 0.504 -0.25)
			(stroke
				(width 0.15)
				(type solid)
			)
			(layer "F.Fab")
		)
		(fp_line
			(start 0.504 0.248)
			(end -0.494 0.248)
			(stroke
				(width 0.15)
				(type solid)
			)
			(layer "F.Fab")
		)
		(fp_line
			(start -0.494 0.248)
			(end -0.494 -0.25)
			(stroke
				(width 0.15)
				(type solid)
			)
			(layer "F.Fab")
		)
		(fp_text user "${REFERENCE}"
			(at -0.932 3.168 90)
			(layer "F.Fab")
			(hide yes)
			(effects
				(font
					(size 0.7 0.7)
					(thickness 0.15)
				)
				(justify left bottom)
			)
		)
		(fp_text user "Author: Antmicro"
			(at -0.932 4.17 90)
			(layer "F.Fab")
			(hide yes)
			(effects
				(font
					(size 0.7 0.7)
					(thickness 0.15)
				)
				(justify left bottom)
			)
		)
		(fp_text user "License: Apache-2.0"
			(at -0.932 5.17 90)
			(layer "F.Fab")
			(hide yes)
			(effects
				(font
					(size 0.7 0.7)
					(thickness 0.15)
				)
				(justify left bottom)
			)
		)
		(pad "1" smd roundrect
			(at -0.48 0 90)
			(size 0.59 0.64)
			(layers "F.Cu" "F.Paste" "F.Mask")
			(roundrect_rratio 0.25)
			(net 99 "+5V")
			(pintype "passive")
		)
		(pad "2" smd roundrect
			(at 0.48 0 90)
			(size 0.59 0.64)
			(layers "F.Cu" "F.Paste" "F.Mask")
			(roundrect_rratio 0.25)
			(net 1 "GND")
			(pintype "passive")
		)
	)
	(footprint "antmicro-footprints:L_Bourns-SRP6050CA"
		(layer "F.Cu")
		(at 56.875 99.485 180)
		(property "Reference" "L4"
			(at 3.34 -3.63 0)
			(layer "F.SilkS")
			(effects
				(font
					(size 0.7 0.7)
					(thickness 0.15)
				)
				(justify right bottom)
			)
		)
		(property "Value" "L_1u_20A_Bourns-SRP6050CA"
			(at -0.025 4.85 0)
			(layer "F.Fab")
			(effects
				(font
					(size 0.7 0.7)
					(thickness 0.15)
				)
				(justify right bottom)
			)
		)
		(property "Footprint" "antmicro-footprints:L_Bourns-SRP6050CA"
			(at 0 0 180)
			(layer "F.Fab")
			(hide yes)
			(effects
				(font
					(size 1.27 1.27)
					(thickness 0.15)
				)
			)
		)
		(property "Datasheet" "https://www.bourns.com/docs/Product-Datasheets/SRP6050CA.pdf"
			(at 0 0 180)
			(layer "F.Fab")
			(hide yes)
			(effects
				(font
					(size 1.27 1.27)
					(thickness 0.15)
				)
			)
		)
		(property "Author" "Antmicro"
			(at 113.75 198.97 0)
			(layer "F.Fab")
			(hide yes)
			(effects
				(font
					(size 1 1)
					(thickness 0.15)
				)
			)
		)
		(property "IMax" "20 A"
			(at 113.75 198.97 0)
			(layer "F.Fab")
			(hide yes)
			(effects
				(font
					(size 1 1)
					(thickness 0.15)
				)
			)
		)
		(property "ISat" "23 A"
			(at 113.75 198.97 0)
			(layer "F.Fab")
			(hide yes)
			(effects
				(font
					(size 1 1)
					(thickness 0.15)
				)
			)
		)
		(property "License" "Apache-2.0"
			(at 113.75 198.97 0)
			(layer "F.Fab")
			(hide yes)
			(effects
				(font
					(size 1 1)
					(thickness 0.15)
				)
			)
		)
		(property "MPN" "SRP6050CA-1R0M"
			(at 113.75 198.97 0)
			(layer "F.Fab")
			(hide yes)
			(effects
				(font
					(size 1 1)
					(thickness 0.15)
				)
			)
		)
		(property "Manufacturer" "Bourns"
			(at 113.75 198.97 0)
			(layer "F.Fab")
			(hide yes)
			(effects
				(font
					(size 1 1)
					(thickness 0.15)
				)
			)
		)
		(property "Size" "6.6x6.4"
			(at 113.75 198.97 0)
			(layer "F.Fab")
			(hide yes)
			(effects
				(font
					(size 1 1)
					(thickness 0.15)
				)
			)
		)
		(property "Val" "1u/20A"
			(at 113.75 198.97 0)
			(layer "F.Fab")
			(hide yes)
			(effects
				(font
					(size 1 1)
					(thickness 0.15)
				)
			)
		)
		(sheetname "Supply")
		(sheetfile "supply.kicad_sch")
		(attr smd)
		(fp_line
			(start 3.2 3.298)
			(end -3.2 3.298)
			(stroke
				(width 0.15)
				(type solid)
			)
			(layer "F.SilkS")
		)
		(fp_line
			(start 3.2 -3.301)
			(end 3.2 3.298)
			(stroke
				(width 0.15)
				(type solid)
			)
			(layer "F.SilkS")
		)
		(fp_line
			(start -3.2 -3.301)
			(end 3.2 -3.301)
			(stroke
				(width 0.15)
				(type solid)
			)
			(layer "F.SilkS")
		)
		(fp_line
			(start -3.2 -3.301)
			(end -3.2 3.298)
			(stroke
				(width 0.15)
				(type solid)
			)
			(layer "F.SilkS")
		)
		(fp_rect
			(start -3.45 -3.55)
			(end 3.45 3.55)
			(stroke
				(width 0.05)
				(type solid)
			)
			(fill none)
			(layer "F.CrtYd")
		)
		(fp_rect
			(start -3.202 -3.301)
			(end 3.2 3.298)
			(stroke
				(width 0.15)
				(type solid)
			)
			(fill none)
			(layer "F.Fab")
		)
		(fp_text user "License: Apache-2.0"
			(at -3.45 8.05 0)
			(layer "F.Fab")
			(hide yes)
			(effects
				(font
					(size 0.7 0.7)
					(thickness 0.15)
				)
				(justify right bottom)
			)
		)
		(fp_text user "${REFERENCE}"
			(at -3.45 6.85 0)
			(layer "F.Fab")
			(hide yes)
			(effects
				(font
					(size 0.7 0.7)
					(thickness 0.15)
				)
				(justify right bottom)
			)
		)
		(fp_text user "Author: Antmicro"
			(at -3.45 9.25 0)
			(layer "F.Fab")
			(hide yes)
			(effects
				(font
					(size 0.7 0.7)
					(thickness 0.15)
				)
				(justify right bottom)
			)
		)
		(pad "1" smd roundrect
			(at -2.025 0 180)
			(size 1.55 5.6)
			(layers "F.Cu" "F.Paste" "F.Mask")
			(roundrect_rratio 0.1)
			(net 763 "/Supply/5V_SW")
			(pintype "passive")
		)
		(pad "2" smd roundrect
			(at 2.025 0 180)
			(size 1.55 5.6)
			(layers "F.Cu" "F.Paste" "F.Mask")
			(roundrect_rratio 0.1)
			(net 761 "/Supply/5V_OUT")
			(pintype "passive")
		)
	)
)
